(kicad_pcb
	(version 20260206)
	(generator "pcbnew")
	(generator_version "10.0")
	(general
		(thickness 1.6)
		(legacy_teardrops no)
	)
	(paper "A4")
	(title_block
		(title "03242023_DA0F0TMBIJ0_F0T_Motherboard_J_brd_V01_OCP.brd")
		(comment 1 "Grand Teton / footprints 4264-4269 of 6105")
	)
	(layers
		(0 "F.Cu" signal "TOP")
		(4 "In1.Cu" signal "GND")
		(6 "In2.Cu" signal "IN1")
		(8 "In3.Cu" signal "GND1")
		(10 "In4.Cu" signal "IN2")
		(12 "In5.Cu" signal "GND2")
		(14 "In6.Cu" signal "IN3")
		(16 "In7.Cu" signal "GND3")
		(18 "In8.Cu" signal "VCC")
		(20 "In9.Cu" signal "VCC1")
		(22 "In10.Cu" signal "GND4")
		(24 "In11.Cu" signal "IN4")
		(26 "In12.Cu" signal "GND5")
		(28 "In13.Cu" signal "IN5")
		(30 "In14.Cu" signal "GND6")
		(32 "In15.Cu" signal "IN6")
		(34 "In16.Cu" signal "GND7")
		(2 "B.Cu" signal "BOTTOM")
		(9 "F.Adhes" user "F.Adhesive")
		(11 "B.Adhes" user "B.Adhesive")
		(13 "F.Paste" user "Package Geometry/Pastemask Top")
		(15 "B.Paste" user "Package Geometry/Pastemask Bottom")
		(5 "F.SilkS" user "Ref Des/Silkscreen Top")
		(7 "B.SilkS" user "Ref Des/Silkscreen Bottom")
		(1 "F.Mask" user "Board Geometry/Soldermask Top")
		(3 "B.Mask" user "Board Geometry/Soldermask Bottom")
		(17 "Dwgs.User" user "User.Drawings")
		(19 "Cmts.User" user "User.Comments")
		(21 "Eco1.User" user "User.Eco1")
		(23 "Eco2.User" user "User.Eco2")
		(25 "Edge.Cuts" user "Board Geometry/Outline")
		(27 "Margin" user)
		(31 "F.CrtYd" user "Package Geometry/Place Bound Top")
		(29 "B.CrtYd" user "Package Geometry/Place Bound Bottom")
		(35 "F.Fab" user "Ref Des/Assembly Top")
		(33 "B.Fab" user "Ref Des/Assembly Bottom")
	)
	(footprint ""
		(layer "B.Cu")
		(at 331.540358 -190.82893 90)
		(property "Reference" "R24"
			(at 0 0 90)
			(layer "B.SilkS")
			(hide yes)
			(effects
				(font
					(size 1.27 1.27)
				)
				(justify mirror)
			)
		)
		(property "Value" ""
			(at 0 0 90)
			(layer "B.Fab")
			(effects
				(font
					(size 1.27 1.27)
				)
				(justify mirror)
			)
		)
		(duplicate_pad_numbers_are_jumpers no)
		(fp_line
			(start 0.7874 -0.4064)
			(end -0.7874 -0.4064)
			(stroke
				(width 0.1524)
				(type default)
			)
			(layer "B.SilkS")
		)
		(fp_line
			(start -0.7874 -0.4064)
			(end -0.7874 0.4064)
			(stroke
				(width 0.1524)
				(type default)
			)
			(layer "B.SilkS")
		)
		(fp_line
			(start 0.7874 0.4064)
			(end 0.7874 -0.4064)
			(stroke
				(width 0.1524)
				(type default)
			)
			(layer "B.SilkS")
		)
		(fp_line
			(start -0.7874 0.4064)
			(end 0.7874 0.4064)
			(stroke
				(width 0.1524)
				(type default)
			)
			(layer "B.SilkS")
		)
		(fp_line
			(start 0.67945 -0.305054)
			(end 0.12065 -0.305054)
			(stroke
				(width 0.1)
				(type default)
			)
			(layer "B.Fab")
		)
		(fp_line
			(start 0.12065 -0.305054)
			(end 0.12065 -0.2794)
			(stroke
				(width 0.1)
				(type default)
			)
			(layer "B.Fab")
		)
		(fp_line
			(start -0.12065 -0.3048)
			(end -0.67945 -0.3048)
			(stroke
				(width 0.1)
				(type default)
			)
			(layer "B.Fab")
		)
		(fp_line
			(start -0.67945 -0.3048)
			(end -0.67945 0.3048)
			(stroke
				(width 0.1)
				(type default)
			)
			(layer "B.Fab")
		)
		(fp_line
			(start 0.12065 -0.2794)
			(end -0.12065 -0.2794)
			(stroke
				(width 0.1)
				(type default)
			)
			(layer "B.Fab")
		)
		(fp_line
			(start -0.12065 -0.2794)
			(end -0.12065 -0.3048)
			(stroke
				(width 0.1)
				(type default)
			)
			(layer "B.Fab")
		)
		(fp_line
			(start 0.12065 0.2794)
			(end 0.12065 0.3048)
			(stroke
				(width 0.1)
				(type default)
			)
			(layer "B.Fab")
		)
		(fp_line
			(start -0.120396 0.2794)
			(end 0.12065 0.2794)
			(stroke
				(width 0.1)
				(type default)
			)
			(layer "B.Fab")
		)
		(fp_line
			(start 0.67945 0.3048)
			(end 0.67945 -0.305054)
			(stroke
				(width 0.1)
				(type default)
			)
			(layer "B.Fab")
		)
		(fp_line
			(start 0.12065 0.3048)
			(end 0.67945 0.3048)
			(stroke
				(width 0.1)
				(type default)
			)
			(layer "B.Fab")
		)
		(fp_line
			(start -0.120396 0.3048)
			(end -0.120396 0.2794)
			(stroke
				(width 0.1)
				(type default)
			)
			(layer "B.Fab")
		)
		(fp_line
			(start -0.67945 0.3048)
			(end -0.120396 0.3048)
			(stroke
				(width 0.1)
				(type default)
			)
			(layer "B.Fab")
		)
		(pad "1" smd circle
			(at 0.40005 0 270)
			(size 0 0)
			(layers "B.Cu" "B.Mask" "B.Paste")
			(net "DBP_CPU0_HOOK8_MBP2_GTL_QS_R_N")
		)
		(pad "2" smd circle
			(at -0.40005 0 270)
			(size 0 0)
			(layers "B.Cu" "B.Mask" "B.Paste")
			(net "DBP_CPU_HOOK8_MBP2_GTL_QS_N")
		)
	)
	(footprint ""
		(layer "B.Cu")
		(at 180.555646 -115.775486 90)
		(property "Reference" "C1906"
			(at 0 0 90)
			(layer "B.SilkS")
			(hide yes)
			(effects
				(font
					(size 1.27 1.27)
				)
				(justify mirror)
			)
		)
		(property "Value" ""
			(at 0 0 90)
			(layer "B.Fab")
			(effects
				(font
					(size 1.27 1.27)
				)
				(justify mirror)
			)
		)
		(duplicate_pad_numbers_are_jumpers no)
		(fp_line
			(start 0.69215 -0.2921)
			(end -0.69215 -0.2921)
			(stroke
				(width 0.1524)
				(type default)
			)
			(layer "B.SilkS")
		)
		(fp_line
			(start -0.69215 -0.2921)
			(end -0.69215 0.2921)
			(stroke
				(width 0.1524)
				(type default)
			)
			(layer "B.SilkS")
		)
		(fp_line
			(start 0.69215 0.2921)
			(end 0.69215 -0.2921)
			(stroke
				(width 0.1524)
				(type default)
			)
			(layer "B.SilkS")
		)
		(fp_line
			(start -0.69215 0.2921)
			(end 0.69215 0.2921)
			(stroke
				(width 0.1524)
				(type default)
			)
			(layer "B.SilkS")
		)
		(fp_line
			(start 0.51435 -0.2794)
			(end -0.51435 -0.2794)
			(stroke
				(width 0.1)
				(type default)
			)
			(layer "B.Fab")
		)
		(fp_line
			(start -0.51435 -0.2794)
			(end -0.51435 0.2794)
			(stroke
				(width 0.1)
				(type default)
			)
			(layer "B.Fab")
		)
		(fp_line
			(start 0.51435 0.2794)
			(end 0.51435 -0.2794)
			(stroke
				(width 0.1)
				(type default)
			)
			(layer "B.Fab")
		)
		(fp_line
			(start -0.51435 0.2794)
			(end 0.51435 0.2794)
			(stroke
				(width 0.1)
				(type default)
			)
			(layer "B.Fab")
		)
		(pad "1" smd circle
			(at 0.40005 0 270)
			(size 0 0)
			(layers "B.Cu" "B.Mask" "B.Paste")
			(net "P3V3_AUX_FPGA_VCCIO1")
		)
		(pad "2" smd circle
			(at -0.40005 0 270)
			(size 0 0)
			(layers "B.Cu" "B.Mask" "B.Paste")
			(net "GND")
		)
		(zone
			(layer "B.Cu")
			(hatch none 0.5)
			(connect_pads
				(clearance 0)
			)
			(min_thickness 0.25)
			(keepout
				(tracks not_allowed)
				(vias allowed)
				(pads allowed)
				(copperpour not_allowed)
				(footprints allowed)
			)
			(placement
				(enabled no)
				(sheetname "")
			)
			(fill
				(thermal_gap 0.5)
				(thermal_bridge_width 0.5)
				(island_removal_mode 0)
			)
			(polygon
				(pts
					(xy 180.643276 -115.965986) (xy 180.701442 -115.874546) (xy 180.701442 -115.675156) (xy 180.643276 -115.584986)
					(xy 180.468016 -115.584986) (xy 180.409596 -115.675156) (xy 180.409596 -115.874546) (xy 180.467762 -115.965986)
				)
			)
		)
	)
	(footprint ""
		(layer "B.Cu")
		(at 73.902062 -181.81955 90)
		(property "Reference" "R299"
			(at 0 0 90)
			(layer "B.SilkS")
			(hide yes)
			(effects
				(font
					(size 1.27 1.27)
				)
				(justify mirror)
			)
		)
		(property "Value" ""
			(at 0 0 90)
			(layer "B.Fab")
			(effects
				(font
					(size 1.27 1.27)
				)
				(justify mirror)
			)
		)
		(duplicate_pad_numbers_are_jumpers no)
		(fp_line
			(start 0.7874 -0.4064)
			(end -0.7874 -0.4064)
			(stroke
				(width 0.1524)
				(type default)
			)
			(layer "B.SilkS")
		)
		(fp_line
			(start -0.7874 -0.4064)
			(end -0.7874 0.4064)
			(stroke
				(width 0.1524)
				(type default)
			)
			(layer "B.SilkS")
		)
		(fp_line
			(start 0.7874 0.4064)
			(end 0.7874 -0.4064)
			(stroke
				(width 0.1524)
				(type default)
			)
			(layer "B.SilkS")
		)
		(fp_line
			(start -0.7874 0.4064)
			(end 0.7874 0.4064)
			(stroke
				(width 0.1524)
				(type default)
			)
			(layer "B.SilkS")
		)
		(fp_line
			(start 0.67945 -0.305054)
			(end 0.12065 -0.305054)
			(stroke
				(width 0.1)
				(type default)
			)
			(layer "B.Fab")
		)
		(fp_line
			(start 0.12065 -0.305054)
			(end 0.12065 -0.2794)
			(stroke
				(width 0.1)
				(type default)
			)
			(layer "B.Fab")
		)
		(fp_line
			(start -0.12065 -0.3048)
			(end -0.67945 -0.3048)
			(stroke
				(width 0.1)
				(type default)
			)
			(layer "B.Fab")
		)
		(fp_line
			(start -0.67945 -0.3048)
			(end -0.67945 0.3048)
			(stroke
				(width 0.1)
				(type default)
			)
			(layer "B.Fab")
		)
		(fp_line
			(start 0.12065 -0.2794)
			(end -0.12065 -0.2794)
			(stroke
				(width 0.1)
				(type default)
			)
			(layer "B.Fab")
		)
		(fp_line
			(start -0.12065 -0.2794)
			(end -0.12065 -0.3048)
			(stroke
				(width 0.1)
				(type default)
			)
			(layer "B.Fab")
		)
		(fp_line
			(start 0.12065 0.2794)
			(end 0.12065 0.3048)
			(stroke
				(width 0.1)
				(type default)
			)
			(layer "B.Fab")
		)
		(fp_line
			(start -0.120396 0.2794)
			(end 0.12065 0.2794)
			(stroke
				(width 0.1)
				(type default)
			)
			(layer "B.Fab")
		)
		(fp_line
			(start 0.67945 0.3048)
			(end 0.67945 -0.305054)
			(stroke
				(width 0.1)
				(type default)
			)
			(layer "B.Fab")
		)
		(fp_line
			(start 0.12065 0.3048)
			(end 0.67945 0.3048)
			(stroke
				(width 0.1)
				(type default)
			)
			(layer "B.Fab")
		)
		(fp_line
			(start -0.120396 0.3048)
			(end -0.120396 0.2794)
			(stroke
				(width 0.1)
				(type default)
			)
			(layer "B.Fab")
		)
		(fp_line
			(start -0.67945 0.3048)
			(end -0.120396 0.3048)
			(stroke
				(width 0.1)
				(type default)
			)
			(layer "B.Fab")
		)
		(pad "1" smd circle
			(at 0.40005 0 270)
			(size 0 0)
			(layers "B.Cu" "B.Mask" "B.Paste")
			(net "H_CPU1_CATERR_LVC1_R_N")
		)
		(pad "2" smd circle
			(at -0.40005 0 270)
			(size 0 0)
			(layers "B.Cu" "B.Mask" "B.Paste")
			(net "H_CPU_CATERR_LVC1_R_N")
		)
	)
	(footprint ""
		(layer "B.Cu")
		(at 213.841838 -195.58635)
		(property "Reference" "C544"
			(at 0 0 0)
			(layer "B.SilkS")
			(hide yes)
			(effects
				(font
					(size 1.27 1.27)
				)
				(justify mirror)
			)
		)
		(property "Value" ""
			(at 0 0 0)
			(layer "B.Fab")
			(effects
				(font
					(size 1.27 1.27)
				)
				(justify mirror)
			)
		)
		(duplicate_pad_numbers_are_jumpers no)
		(fp_line
			(start -0.7874 -0.4064)
			(end -0.7874 0.4064)
			(stroke
				(width 0.1524)
				(type default)
			)
			(layer "B.SilkS")
		)
		(fp_line
			(start -0.7874 0.4064)
			(end 0.7874 0.4064)
			(stroke
				(width 0.1524)
				(type default)
			)
			(layer "B.SilkS")
		)
		(fp_line
			(start 0.7874 -0.4064)
			(end -0.7874 -0.4064)
			(stroke
				(width 0.1524)
				(type default)
			)
			(layer "B.SilkS")
		)
		(fp_line
			(start 0.7874 0.4064)
			(end 0.7874 -0.4064)
			(stroke
				(width 0.1524)
				(type default)
			)
			(layer "B.SilkS")
		)
		(fp_line
			(start -0.67945 -0.3048)
			(end -0.67945 0.3048)
			(stroke
				(width 0.1)
				(type default)
			)
			(layer "B.Fab")
		)
		(fp_line
			(start -0.67945 0.3048)
			(end -0.120396 0.3048)
			(stroke
				(width 0.1)
				(type default)
			)
			(layer "B.Fab")
		)
		(fp_line
			(start -0.12065 -0.3048)
			(end -0.67945 -0.3048)
			(stroke
				(width 0.1)
				(type default)
			)
			(layer "B.Fab")
		)
		(fp_line
			(start -0.12065 -0.2794)
			(end -0.12065 -0.3048)
			(stroke
				(width 0.1)
				(type default)
			)
			(layer "B.Fab")
		)
		(fp_line
			(start -0.120396 0.2794)
			(end 0.12065 0.2794)
			(stroke
				(width 0.1)
				(type default)
			)
			(layer "B.Fab")
		)
		(fp_line
			(start -0.120396 0.3048)
			(end -0.120396 0.2794)
			(stroke
				(width 0.1)
				(type default)
			)
			(layer "B.Fab")
		)
		(fp_line
			(start 0.12065 -0.305054)
			(end 0.12065 -0.2794)
			(stroke
				(width 0.1)
				(type default)
			)
			(layer "B.Fab")
		)
		(fp_line
			(start 0.12065 -0.2794)
			(end -0.12065 -0.2794)
			(stroke
				(width 0.1)
				(type default)
			)
			(layer "B.Fab")
		)
		(fp_line
			(start 0.12065 0.2794)
			(end 0.12065 0.3048)
			(stroke
				(width 0.1)
				(type default)
			)
			(layer "B.Fab")
		)
		(fp_line
			(start 0.12065 0.3048)
			(end 0.67945 0.3048)
			(stroke
				(width 0.1)
				(type default)
			)
			(layer "B.Fab")
		)
		(fp_line
			(start 0.67945 -0.305054)
			(end 0.12065 -0.305054)
			(stroke
				(width 0.1)
				(type default)
			)
			(layer "B.Fab")
		)
		(fp_line
			(start 0.67945 0.3048)
			(end 0.67945 -0.305054)
			(stroke
				(width 0.1)
				(type default)
			)
			(layer "B.Fab")
		)
		(pad "1" smd circle
			(at 0.40005 0 180)
			(size 0 0)
			(layers "B.Cu" "B.Mask" "B.Paste")
			(net "P3V3_AUX")
		)
		(pad "2" smd circle
			(at -0.40005 0 180)
			(size 0 0)
			(layers "B.Cu" "B.Mask" "B.Paste")
			(net "GND")
		)
	)
	(footprint ""
		(layer "B.Cu")
		(at 230.48468 -118.760748 -90)
		(property "Reference" "R3636"
			(at 0 0 90)
			(layer "B.SilkS")
			(hide yes)
			(effects
				(font
					(size 1.27 1.27)
				)
				(justify mirror)
			)
		)
		(property "Value" ""
			(at 0 0 90)
			(layer "B.Fab")
			(effects
				(font
					(size 1.27 1.27)
				)
				(justify mirror)
			)
		)
		(duplicate_pad_numbers_are_jumpers no)
		(fp_line
			(start -0.7874 0.4064)
			(end 0.7874 0.4064)
			(stroke
				(width 0.1524)
				(type default)
			)
			(layer "B.SilkS")
		)
		(fp_line
			(start 0.7874 0.4064)
			(end 0.7874 -0.4064)
			(stroke
				(width 0.1524)
				(type default)
			)
			(layer "B.SilkS")
		)
		(fp_line
			(start -0.7874 -0.4064)
			(end -0.7874 0.4064)
			(stroke
				(width 0.1524)
				(type default)
			)
			(layer "B.SilkS")
		)
		(fp_line
			(start 0.7874 -0.4064)
			(end -0.7874 -0.4064)
			(stroke
				(width 0.1524)
				(type default)
			)
			(layer "B.SilkS")
		)
		(fp_line
			(start -0.67945 0.3048)
			(end -0.120396 0.3048)
			(stroke
				(width 0.1)
				(type default)
			)
			(layer "B.Fab")
		)
		(fp_line
			(start -0.120396 0.3048)
			(end -0.120396 0.2794)
			(stroke
				(width 0.1)
				(type default)
			)
			(layer "B.Fab")
		)
		(fp_line
			(start 0.12065 0.3048)
			(end 0.67945 0.3048)
			(stroke
				(width 0.1)
				(type default)
			)
			(layer "B.Fab")
		)
		(fp_line
			(start 0.67945 0.3048)
			(end 0.67945 -0.305054)
			(stroke
				(width 0.1)
				(type default)
			)
			(layer "B.Fab")
		)
		(fp_line
			(start -0.120396 0.2794)
			(end 0.12065 0.2794)
			(stroke
				(width 0.1)
				(type default)
			)
			(layer "B.Fab")
		)
		(fp_line
			(start 0.12065 0.2794)
			(end 0.12065 0.3048)
			(stroke
				(width 0.1)
				(type default)
			)
			(layer "B.Fab")
		)
		(fp_line
			(start -0.12065 -0.2794)
			(end -0.12065 -0.3048)
			(stroke
				(width 0.1)
				(type default)
			)
			(layer "B.Fab")
		)
		(fp_line
			(start 0.12065 -0.2794)
			(end -0.12065 -0.2794)
			(stroke
				(width 0.1)
				(type default)
			)
			(layer "B.Fab")
		)
		(fp_line
			(start -0.67945 -0.3048)
			(end -0.67945 0.3048)
			(stroke
				(width 0.1)
				(type default)
			)
			(layer "B.Fab")
		)
		(fp_line
			(start -0.12065 -0.3048)
			(end -0.67945 -0.3048)
			(stroke
				(width 0.1)
				(type default)
			)
			(layer "B.Fab")
		)
		(fp_line
			(start 0.12065 -0.305054)
			(end 0.12065 -0.2794)
			(stroke
				(width 0.1)
				(type default)
			)
			(layer "B.Fab")
		)
		(fp_line
			(start 0.67945 -0.305054)
			(end 0.12065 -0.305054)
			(stroke
				(width 0.1)
				(type default)
			)
			(layer "B.Fab")
		)
		(pad "1" smd circle
			(at 0.40005 0 90)
			(size 0 0)
			(layers "B.Cu" "B.Mask" "B.Paste")
			(net "OCP_SFF_CLK_OE_N")
		)
		(pad "2" smd circle
			(at -0.40005 0 90)
			(size 0 0)
			(layers "B.Cu" "B.Mask" "B.Paste")
			(net "FM_DB2000_11_OE_N")
		)
	)
	(footprint ""
		(layer "B.Cu")
		(at 197.437502 -109.89691 180)
		(property "Reference" "R1388"
			(at 0 0 0)
			(layer "B.SilkS")
			(hide yes)
			(effects
				(font
					(size 1.27 1.27)
				)
				(justify mirror)
			)
		)
		(property "Value" ""
			(at 0 0 0)
			(layer "B.Fab")
			(effects
				(font
					(size 1.27 1.27)
				)
				(justify mirror)
			)
		)
		(duplicate_pad_numbers_are_jumpers no)
		(fp_line
			(start 0.7874 0.4064)
			(end 0.7874 -0.4064)
			(stroke
				(width 0.1524)
				(type default)
			)
			(layer "B.SilkS")
		)
		(fp_line
			(start 0.7874 -0.4064)
			(end -0.7874 -0.4064)
			(stroke
				(width 0.1524)
				(type default)
			)
			(layer "B.SilkS")
		)
		(fp_line
			(start -0.7874 0.4064)
			(end 0.7874 0.4064)
			(stroke
				(width 0.1524)
				(type default)
			)
			(layer "B.SilkS")
		)
		(fp_line
			(start -0.7874 -0.4064)
			(end -0.7874 0.4064)
			(stroke
				(width 0.1524)
				(type default)
			)
			(layer "B.SilkS")
		)
		(fp_line
			(start 0.67945 0.3048)
			(end 0.67945 -0.305054)
			(stroke
				(width 0.1)
				(type default)
			)
			(layer "B.Fab")
		)
		(fp_line
			(start 0.67945 -0.305054)
			(end 0.12065 -0.305054)
			(stroke
				(width 0.1)
				(type default)
			)
			(layer "B.Fab")
		)
		(fp_line
			(start 0.12065 0.3048)
			(end 0.67945 0.3048)
			(stroke
				(width 0.1)
				(type default)
			)
			(layer "B.Fab")
		)
		(fp_line
			(start 0.12065 0.2794)
			(end 0.12065 0.3048)
			(stroke
				(width 0.1)
				(type default)
			)
			(layer "B.Fab")
		)
		(fp_line
			(start 0.12065 -0.2794)
			(end -0.12065 -0.2794)
			(stroke
				(width 0.1)
				(type default)
			)
			(layer "B.Fab")
		)
		(fp_line
			(start 0.12065 -0.305054)
			(end 0.12065 -0.2794)
			(stroke
				(width 0.1)
				(type default)
			)
			(layer "B.Fab")
		)
		(fp_line
			(start -0.120396 0.3048)
			(end -0.120396 0.2794)
			(stroke
				(width 0.1)
				(type default)
			)
			(layer "B.Fab")
		)
		(fp_line
			(start -0.120396 0.2794)
			(end 0.12065 0.2794)
			(stroke
				(width 0.1)
				(type default)
			)
			(layer "B.Fab")
		)
		(fp_line
			(start -0.12065 -0.2794)
			(end -0.12065 -0.3048)
			(stroke
				(width 0.1)
				(type default)
			)
			(layer "B.Fab")
		)
		(fp_line
			(start -0.12065 -0.3048)
			(end -0.67945 -0.3048)
			(stroke
				(width 0.1)
				(type default)
			)
			(layer "B.Fab")
		)
		(fp_line
			(start -0.67945 0.3048)
			(end -0.120396 0.3048)
			(stroke
				(width 0.1)
				(type default)
			)
			(layer "B.Fab")
		)
		(fp_line
			(start -0.67945 -0.3048)
			(end -0.67945 0.3048)
			(stroke
				(width 0.1)
				(type default)
			)
			(layer "B.Fab")
		)
		(pad "1" smd circle
			(at 0.40005 0)
			(size 0 0)
			(layers "B.Cu" "B.Mask" "B.Paste")
			(net "PWRGD_DRAMPWRGD_CPU1_EF_R_LVC1")
		)
		(pad "2" smd circle
			(at -0.40005 0)
			(size 0 0)
			(layers "B.Cu" "B.Mask" "B.Paste")
			(net "GND")
		)
	)
)
